# BASEBOARD_FAB2 (Tioga Pass) — schematic netlist excerpt (pin names and nets, part order shuffled) for the footprints in the layout excerpt that follows; sources: Cadence DE-HDL packaged netlist, KiCad conversion of Wiwynn_Tioga_Pass_MB.brd

C7C20  SC1U10V2KX-4-GP  10%  pkg SMD-BCG6  page 212 : \1\ = P5V_STBY ; \2\ = GND
C3L26  CAP_A  22.0UF 4V 20% X6S  pkg 0603V  page 132 : A = PVNN_PCH_STBY ; B = GND
CR9P1  DIODE  BAT54WS IC  pkg SMLF  page 200 : C = IRQ_UV_DETECT_N ; A = FM_DISABLE_FAN_N

(kicad_pcb
	(version 20260206)
	(generator "pcbnew")
	(generator_version "10.0")
	(general
		(thickness 1.6)
		(legacy_teardrops no)
	)
	(paper "A4")
	(title_block
		(title "Wiwynn_Tioga_Pass_MB.brd")
		(comment 1 "Tioga Pass / footprints 4604-4606 of 4770")
	)
	(layers
		(0 "F.Cu" signal "TOP")
		(4 "In1.Cu" signal "L2GND")
		(6 "In2.Cu" signal "L3")
		(8 "In3.Cu" signal "L4GND")
		(10 "In4.Cu" signal "L5")
		(12 "In5.Cu" signal "L6GND")
		(14 "In6.Cu" signal "L7VCC")
		(16 "In7.Cu" signal "L8VCC")
		(18 "In8.Cu" signal "L9GND")
		(20 "In9.Cu" signal "L10")
		(22 "In10.Cu" signal "L11GND")
		(24 "In11.Cu" signal "L12")
		(26 "In12.Cu" signal "L13GND")
		(2 "B.Cu" signal "BOTTOM")
		(9 "F.Adhes" user "F.Adhesive")
		(11 "B.Adhes" user "B.Adhesive")
		(13 "F.Paste" user "Package Geometry/Pastemask Top")
		(15 "B.Paste" user "Package Geometry/Pastemask Bottom")
		(5 "F.SilkS" user "Ref Des/Silkscreen Top")
		(7 "B.SilkS" user "Ref Des/Silkscreen Bottom")
		(1 "F.Mask" user "Board Geometry/Soldermask Top")
		(3 "B.Mask" user "Board Geometry/Soldermask Bottom")
		(17 "Dwgs.User" user "User.Drawings")
		(19 "Cmts.User" user "User.Comments")
		(21 "Eco1.User" user "User.Eco1")
		(23 "Eco2.User" user "User.Eco2")
		(25 "Edge.Cuts" user "Board Geometry/Outline")
		(27 "Margin" user)
		(31 "F.CrtYd" user "Package Geometry/Place Bound Top")
		(29 "B.CrtYd" user "Package Geometry/Place Bound Bottom")
		(35 "F.Fab" user "Ref Des/Assembly Top")
		(33 "B.Fab" user "Ref Des/Assembly Bottom")
	)
	(footprint ""
		(layer "B.Cu")
		(at 347.346778 -101.449632 -90)
		(property "Reference" "C7C20"
			(at 0 0 90)
			(layer "B.SilkS")
			(hide yes)
			(effects
				(font
					(size 1.27 1.27)
				)
				(justify mirror)
			)
		)
		(property "Value" "*"
			(at -1.1811 -2.8194 270)
			(unlocked yes)
			(layer "B.Fab")
			(hide yes)
			(effects
				(font
					(size 1.27 1.016)
					(thickness 0.1524)
				)
				(justify mirror)
			)
		)
		(property "Device Type" "SC1U10V2KX-4-GP_SMD-BCG6-SC1U1A"
			(at -1.1811 -4.3434 270)
			(unlocked yes)
			(layer "B.Fab")
			(hide yes)
			(effects
				(font
					(size 1.27 1.016)
					(thickness 0.1524)
				)
				(justify mirror)
			)
		)
		(duplicate_pad_numbers_are_jumpers no)
		(fp_rect
			(start 0.4318 0.9525)
			(end -0.4318 -0.9525)
			(stroke
				(width 0)
				(type default)
			)
			(fill no)
			(layer "B.CrtYd")
		)
		(fp_rect
			(start 0.4318 0.9525)
			(end -0.4318 -0.9525)
			(stroke
				(width 0)
				(type default)
			)
			(fill no)
			(layer "B.Fab")
		)
		(pad "1" smd custom
			(at 0 -0.4445 90)
			(size 0.1524 0.1524)
			(layers "B.Cu" "B.Mask" "B.Paste")
			(net "P5V_STBY")
			(options
				(clearance outline)
				(anchor circle)
			)
			(primitives
				(gr_poly
					(pts
						(arc
							(start 0.3048 0.2032)
							(mid 0.275042 0.275042)
							(end 0.2032 0.3048)
						)
						(arc
							(start -0.2032 0.3048)
							(mid -0.275042 0.275042)
							(end -0.3048 0.2032)
						)
						(arc
							(start -0.3048 -0.2032)
							(mid -0.275042 -0.275042)
							(end -0.2032 -0.3048)
						)
						(arc
							(start 0.2032 -0.3048)
							(mid 0.275042 -0.275042)
							(end 0.3048 -0.2032)
						)
					)
					(width 0)
					(fill yes)
				)
			)
		)
		(pad "2" smd custom
			(at 0 0.4445 90)
			(size 0.1524 0.1524)
			(layers "B.Cu" "B.Mask" "B.Paste")
			(net "GND")
			(options
				(clearance outline)
				(anchor circle)
			)
			(primitives
				(gr_poly
					(pts
						(arc
							(start 0.3048 0.2032)
							(mid 0.275042 0.275042)
							(end 0.2032 0.3048)
						)
						(arc
							(start -0.2032 0.3048)
							(mid -0.275042 0.275042)
							(end -0.3048 0.2032)
						)
						(arc
							(start -0.3048 -0.2032)
							(mid -0.275042 -0.275042)
							(end -0.2032 -0.3048)
						)
						(arc
							(start 0.2032 -0.3048)
							(mid 0.275042 -0.275042)
							(end 0.3048 -0.2032)
						)
					)
					(width 0)
					(fill yes)
				)
			)
		)
	)
	(footprint ""
		(layer "B.Cu")
		(at 23.87854 -87.24138 90)
		(property "Reference" "CR9P1"
			(at 0 0 90)
			(layer "B.SilkS")
			(hide yes)
			(effects
				(font
					(size 1.27 1.27)
				)
				(justify mirror)
			)
		)
		(property "Value" ""
			(at 0 0 90)
			(layer "B.Fab")
			(effects
				(font
					(size 1.27 1.27)
				)
				(justify mirror)
			)
		)
		(duplicate_pad_numbers_are_jumpers no)
		(fp_line
			(start -0.546862 -0.332486)
			(end -0.546862 0.790956)
			(stroke
				(width 0.1524)
				(type default)
			)
			(layer "B.SilkS")
		)
		(fp_line
			(start -0.546862 0.790956)
			(end -1.027684 1.623822)
			(stroke
				(width 0.1524)
				(type default)
			)
			(layer "B.SilkS")
		)
		(fp_line
			(start -1.027684 0.790956)
			(end -0.06604 0.790956)
			(stroke
				(width 0.1524)
				(type default)
			)
			(layer "B.SilkS")
		)
		(fp_line
			(start -0.06604 1.623822)
			(end -0.546862 0.790956)
			(stroke
				(width 0.1524)
				(type default)
			)
			(layer "B.SilkS")
		)
		(fp_line
			(start -0.546862 1.623822)
			(end -0.06604 1.623822)
			(stroke
				(width 0.1524)
				(type default)
			)
			(layer "B.SilkS")
		)
		(fp_line
			(start -1.027684 1.623822)
			(end -0.546862 1.623822)
			(stroke
				(width 0.1524)
				(type default)
			)
			(layer "B.SilkS")
		)
		(fp_line
			(start -0.546862 2.535428)
			(end -0.546862 1.623822)
			(stroke
				(width 0.1524)
				(type default)
			)
			(layer "B.SilkS")
		)
		(fp_poly
			(pts
				(xy 0.67437 0.24384) (xy 0.67437 2.04216) (xy -0.67437 2.04216) (xy -0.67437 0.24384)
			)
			(stroke
				(width 0)
				(type default)
			)
			(fill no)
			(layer "B.CrtYd")
		)
		(fp_line
			(start 0.67437 0.24384)
			(end 0.67437 2.04216)
			(stroke
				(width 0.1)
				(type default)
			)
			(layer "B.Fab")
		)
		(fp_line
			(start -0.67437 0.24384)
			(end 0.67437 0.24384)
			(stroke
				(width 0.1)
				(type default)
			)
			(layer "B.Fab")
		)
		(fp_line
			(start -0.546862 0.790956)
			(end -0.546862 -0.332486)
			(stroke
				(width 0.1)
				(type default)
			)
			(layer "B.Fab")
		)
		(fp_line
			(start -0.546862 0.790956)
			(end -1.027684 1.623822)
			(stroke
				(width 0.1)
				(type default)
			)
			(layer "B.Fab")
		)
		(fp_line
			(start -1.027684 0.790956)
			(end -0.06604 0.790956)
			(stroke
				(width 0.1)
				(type default)
			)
			(layer "B.Fab")
		)
		(fp_line
			(start -0.06604 1.623822)
			(end -0.546862 0.790956)
			(stroke
				(width 0.1)
				(type default)
			)
			(layer "B.Fab")
		)
		(fp_line
			(start -0.546862 1.623822)
			(end -0.546862 2.535428)
			(stroke
				(width 0.1)
				(type default)
			)
			(layer "B.Fab")
		)
		(fp_line
			(start -1.027684 1.623822)
			(end -0.06604 1.623822)
			(stroke
				(width 0.1)
				(type default)
			)
			(layer "B.Fab")
		)
		(fp_line
			(start 0.67437 2.04216)
			(end -0.67437 2.04216)
			(stroke
				(width 0.1)
				(type default)
			)
			(layer "B.Fab")
		)
		(fp_line
			(start -0.67437 2.04216)
			(end -0.67437 0.24384)
			(stroke
				(width 0.1)
				(type default)
			)
			(layer "B.Fab")
		)
		(pad "1" smd rect
			(at 0 0 270)
			(size 0.4064 1.016)
			(layers "B.Cu" "B.Mask" "B.Paste")
			(net "IRQ_UV_DETECT_N")
		)
		(pad "2" smd rect
			(at 0 2.286 270)
			(size 0.4064 1.016)
			(layers "B.Cu" "B.Mask" "B.Paste")
			(net "FM_DISABLE_FAN_N")
		)
	)
	(footprint ""
		(layer "B.Cu")
		(at 382.0922 -137.541)
		(property "Reference" "C3L26"
			(at 0 0 0)
			(layer "B.SilkS")
			(hide yes)
			(effects
				(font
					(size 1.27 1.27)
				)
				(justify mirror)
			)
		)
		(property "Value" ""
			(at 0 0 0)
			(layer "B.Fab")
			(effects
				(font
					(size 1.27 1.27)
				)
				(justify mirror)
			)
		)
		(duplicate_pad_numbers_are_jumpers no)
		(fp_poly
			(pts
				(xy 0.4953 -0.2032) (xy -0.4953 -0.2032) (xy -0.4953 1.6002) (xy 0.4953 1.6002)
			)
			(stroke
				(width 0)
				(type default)
			)
			(fill no)
			(layer "B.CrtYd")
		)
		(fp_line
			(start -0.4953 -0.2032)
			(end -0.4953 1.6002)
			(stroke
				(width 0.1)
				(type default)
			)
			(layer "B.Fab")
		)
		(fp_line
			(start -0.4953 1.6002)
			(end 0.4953 1.6002)
			(stroke
				(width 0.1)
				(type default)
			)
			(layer "B.Fab")
		)
		(fp_line
			(start 0.4953 -0.2032)
			(end -0.4953 -0.2032)
			(stroke
				(width 0.1)
				(type default)
			)
			(layer "B.Fab")
		)
		(fp_line
			(start 0.4953 1.6002)
			(end 0.4953 -0.2032)
			(stroke
				(width 0.1)
				(type default)
			)
			(layer "B.Fab")
		)
		(pad "1" smd rect
			(at 0 0 180)
			(size 0.762 0.889)
			(layers "B.Cu" "B.Mask" "B.Paste")
			(net "PVNN_PCH_STBY")
		)
		(pad "2" smd rect
			(at 0 1.397 180)
			(size 0.762 0.889)
			(layers "B.Cu" "B.Mask" "B.Paste")
			(net "GND")
		)
		(zone
			(layer "B.Cu")
			(hatch none 0.5)
			(connect_pads
				(clearance 0)
			)
			(min_thickness 0.25)
			(keepout
				(tracks not_allowed)
				(vias allowed)
				(pads allowed)
				(copperpour not_allowed)
				(footprints allowed)
			)
			(placement
				(enabled no)
				(sheetname "")
			)
			(fill
				(thermal_gap 0.5)
				(thermal_bridge_width 0.5)
				(island_removal_mode 0)
			)
			(polygon
				(pts
					(xy 382.4732 -137.0965) (xy 381.7112 -137.0965) (xy 381.7112 -136.5885) (xy 382.4732 -136.5885)
				)
			)
		)
	)
)
